# T6G (Grand Teton) — schematic netlist excerpt (pin names and nets, part order shuffled) for the footprints in the layout excerpt that follows; sources: Cadence DE-HDL packaged netlist, KiCad conversion of 04192023_DAF0TMB3IC0_F0TG_MB_C_brd_V02_OCP.brd

PR512  Q_RES  1.5 1% EMPTY  pkg 0402LF  page 218 : A = SW_PVDDCR_CPU1_P1_SW1_RC ; B = GND
C755  Q_CAP_DIFFBUS  DIFF BUS_0.22UF 6.3V 20% X6S  pkg C0201  page 66 : \1\ = P5E_CPU1_P2_TX_C_DP<9> ; \2\ = P5E_CPU1_P2_TX_DP<9>
R6216  Q_RES  10K 1% EMPTY  pkg 0402LF  page 176 : A = USB_CPU0_HUB1_MODE_SEL0 ; B = GND

(kicad_pcb
	(version 20260206)
	(generator "pcbnew")
	(generator_version "10.0")
	(general
		(thickness 1.6)
		(legacy_teardrops no)
	)
	(paper "A4")
	(title_block
		(title "04192023_DAF0TMB3IC0_F0TG_MB_C_brd_V02_OCP.brd")
		(comment 1 "Grand Teton / footprints 3896-3898 of 8354")
	)
	(layers
		(0 "F.Cu" signal "TOP")
		(4 "In1.Cu" signal "GND")
		(6 "In2.Cu" signal "IN1")
		(8 "In3.Cu" signal "GND1")
		(10 "In4.Cu" signal "IN2")
		(12 "In5.Cu" signal "GND2")
		(14 "In6.Cu" signal "IN3")
		(16 "In7.Cu" signal "GND3")
		(18 "In8.Cu" signal "VCC")
		(20 "In9.Cu" signal "VCC1")
		(22 "In10.Cu" signal "GND4")
		(24 "In11.Cu" signal "IN4")
		(26 "In12.Cu" signal "GND5")
		(28 "In13.Cu" signal "IN5")
		(30 "In14.Cu" signal "GND6")
		(32 "In15.Cu" signal "IN6")
		(34 "In16.Cu" signal "GND7")
		(2 "B.Cu" signal "BOTTOM")
		(9 "F.Adhes" user "F.Adhesive")
		(11 "B.Adhes" user "B.Adhesive")
		(13 "F.Paste" user "Package Geometry/Pastemask Top")
		(15 "B.Paste" user "Package Geometry/Pastemask Bottom")
		(5 "F.SilkS" user "Ref Des/Silkscreen Top")
		(7 "B.SilkS" user "Ref Des/Silkscreen Bottom")
		(1 "F.Mask" user "Board Geometry/Soldermask Top")
		(3 "B.Mask" user "Board Geometry/Soldermask Bottom")
		(17 "Dwgs.User" user "User.Drawings")
		(19 "Cmts.User" user "User.Comments")
		(21 "Eco1.User" user "User.Eco1")
		(23 "Eco2.User" user "User.Eco2")
		(25 "Edge.Cuts" user "Board Geometry/Outline")
		(27 "Margin" user)
		(31 "F.CrtYd" user "Package Geometry/Place Bound Top")
		(29 "B.CrtYd" user "Package Geometry/Place Bound Bottom")
		(35 "F.Fab" user "Ref Des/Assembly Top")
		(33 "B.Fab" user "Ref Des/Assembly Bottom")
	)
	(footprint ""
		(layer "F.Cu")
		(at 83.445096 -333.24419 90)
		(property "Reference" "PR512"
			(at 0 0 90)
			(layer "F.SilkS")
			(hide yes)
			(effects
				(font
					(size 1.27 1.27)
				)
			)
		)
		(property "Value" ""
			(at 0 0 90)
			(layer "F.Fab")
			(effects
				(font
					(size 1.27 1.27)
				)
			)
		)
		(duplicate_pad_numbers_are_jumpers no)
		(fp_line
			(start 0.7874 -0.4064)
			(end 0.7874 0.4064)
			(stroke
				(width 0.1524)
				(type default)
			)
			(layer "F.SilkS")
		)
		(fp_line
			(start -0.7874 -0.4064)
			(end 0.7874 -0.4064)
			(stroke
				(width 0.1524)
				(type default)
			)
			(layer "F.SilkS")
		)
		(fp_line
			(start 0.7874 0.4064)
			(end -0.7874 0.4064)
			(stroke
				(width 0.1524)
				(type default)
			)
			(layer "F.SilkS")
		)
		(fp_line
			(start -0.7874 0.4064)
			(end -0.7874 -0.4064)
			(stroke
				(width 0.1524)
				(type default)
			)
			(layer "F.SilkS")
		)
		(fp_line
			(start -0.12065 -0.305054)
			(end -0.12065 -0.2794)
			(stroke
				(width 0.1)
				(type default)
			)
			(layer "F.Fab")
		)
		(fp_line
			(start -0.67945 -0.305054)
			(end -0.12065 -0.305054)
			(stroke
				(width 0.1)
				(type default)
			)
			(layer "F.Fab")
		)
		(fp_line
			(start 0.67945 -0.3048)
			(end 0.67945 0.3048)
			(stroke
				(width 0.1)
				(type default)
			)
			(layer "F.Fab")
		)
		(fp_line
			(start 0.12065 -0.3048)
			(end 0.67945 -0.3048)
			(stroke
				(width 0.1)
				(type default)
			)
			(layer "F.Fab")
		)
		(fp_line
			(start 0.12065 -0.2794)
			(end 0.12065 -0.3048)
			(stroke
				(width 0.1)
				(type default)
			)
			(layer "F.Fab")
		)
		(fp_line
			(start -0.12065 -0.2794)
			(end 0.12065 -0.2794)
			(stroke
				(width 0.1)
				(type default)
			)
			(layer "F.Fab")
		)
		(fp_line
			(start 0.120396 0.2794)
			(end -0.12065 0.2794)
			(stroke
				(width 0.1)
				(type default)
			)
			(layer "F.Fab")
		)
		(fp_line
			(start -0.12065 0.2794)
			(end -0.12065 0.3048)
			(stroke
				(width 0.1)
				(type default)
			)
			(layer "F.Fab")
		)
		(fp_line
			(start 0.67945 0.3048)
			(end 0.120396 0.3048)
			(stroke
				(width 0.1)
				(type default)
			)
			(layer "F.Fab")
		)
		(fp_line
			(start 0.120396 0.3048)
			(end 0.120396 0.2794)
			(stroke
				(width 0.1)
				(type default)
			)
			(layer "F.Fab")
		)
		(fp_line
			(start -0.12065 0.3048)
			(end -0.67945 0.3048)
			(stroke
				(width 0.1)
				(type default)
			)
			(layer "F.Fab")
		)
		(fp_line
			(start -0.67945 0.3048)
			(end -0.67945 -0.305054)
			(stroke
				(width 0.1)
				(type default)
			)
			(layer "F.Fab")
		)
		(pad "1" smd circle
			(at -0.40005 0 90)
			(size 0 0)
			(layers "F.Cu" "F.Mask" "F.Paste")
			(net "SW_PVDDCR_CPU1_P1_SW1_RC")
		)
		(pad "2" smd circle
			(at 0.40005 0 90)
			(size 0 0)
			(layers "F.Cu" "F.Mask" "F.Paste")
			(net "GND")
		)
	)
	(footprint ""
		(layer "F.Cu")
		(at 137.971784 -49.595024)
		(property "Reference" "R6216"
			(at 0 0 0)
			(layer "F.SilkS")
			(hide yes)
			(effects
				(font
					(size 1.27 1.27)
				)
			)
		)
		(property "Value" ""
			(at 0 0 0)
			(layer "F.Fab")
			(effects
				(font
					(size 1.27 1.27)
				)
			)
		)
		(duplicate_pad_numbers_are_jumpers no)
		(fp_line
			(start -0.7874 -0.4064)
			(end 0.7874 -0.4064)
			(stroke
				(width 0.1524)
				(type default)
			)
			(layer "F.SilkS")
		)
		(fp_line
			(start -0.7874 0.4064)
			(end -0.7874 -0.4064)
			(stroke
				(width 0.1524)
				(type default)
			)
			(layer "F.SilkS")
		)
		(fp_line
			(start 0.7874 -0.4064)
			(end 0.7874 0.4064)
			(stroke
				(width 0.1524)
				(type default)
			)
			(layer "F.SilkS")
		)
		(fp_line
			(start 0.7874 0.4064)
			(end -0.7874 0.4064)
			(stroke
				(width 0.1524)
				(type default)
			)
			(layer "F.SilkS")
		)
		(fp_line
			(start -0.67945 -0.305054)
			(end -0.12065 -0.305054)
			(stroke
				(width 0.1)
				(type default)
			)
			(layer "F.Fab")
		)
		(fp_line
			(start -0.67945 0.3048)
			(end -0.67945 -0.305054)
			(stroke
				(width 0.1)
				(type default)
			)
			(layer "F.Fab")
		)
		(fp_line
			(start -0.12065 -0.305054)
			(end -0.12065 -0.2794)
			(stroke
				(width 0.1)
				(type default)
			)
			(layer "F.Fab")
		)
		(fp_line
			(start -0.12065 -0.2794)
			(end 0.12065 -0.2794)
			(stroke
				(width 0.1)
				(type default)
			)
			(layer "F.Fab")
		)
		(fp_line
			(start -0.12065 0.2794)
			(end -0.12065 0.3048)
			(stroke
				(width 0.1)
				(type default)
			)
			(layer "F.Fab")
		)
		(fp_line
			(start -0.12065 0.3048)
			(end -0.67945 0.3048)
			(stroke
				(width 0.1)
				(type default)
			)
			(layer "F.Fab")
		)
		(fp_line
			(start 0.120396 0.2794)
			(end -0.12065 0.2794)
			(stroke
				(width 0.1)
				(type default)
			)
			(layer "F.Fab")
		)
		(fp_line
			(start 0.120396 0.3048)
			(end 0.120396 0.2794)
			(stroke
				(width 0.1)
				(type default)
			)
			(layer "F.Fab")
		)
		(fp_line
			(start 0.12065 -0.3048)
			(end 0.67945 -0.3048)
			(stroke
				(width 0.1)
				(type default)
			)
			(layer "F.Fab")
		)
		(fp_line
			(start 0.12065 -0.2794)
			(end 0.12065 -0.3048)
			(stroke
				(width 0.1)
				(type default)
			)
			(layer "F.Fab")
		)
		(fp_line
			(start 0.67945 -0.3048)
			(end 0.67945 0.3048)
			(stroke
				(width 0.1)
				(type default)
			)
			(layer "F.Fab")
		)
		(fp_line
			(start 0.67945 0.3048)
			(end 0.120396 0.3048)
			(stroke
				(width 0.1)
				(type default)
			)
			(layer "F.Fab")
		)
		(pad "1" smd circle
			(at -0.40005 0)
			(size 0 0)
			(layers "F.Cu" "F.Mask" "F.Paste")
			(net "USB_CPU0_HUB1_MODE_SEL0")
		)
		(pad "2" smd circle
			(at 0.40005 0)
			(size 0 0)
			(layers "F.Cu" "F.Mask" "F.Paste")
			(net "GND")
		)
	)
	(footprint ""
		(layer "F.Cu")
		(at 157.933644 -370.57203 -90)
		(property "Reference" "C755"
			(at 0 0 270)
			(layer "F.SilkS")
			(hide yes)
			(effects
				(font
					(size 1.27 1.27)
				)
			)
		)
		(property "Value" ""
			(at 0 0 270)
			(layer "F.Fab")
			(effects
				(font
					(size 1.27 1.27)
				)
			)
		)
		(duplicate_pad_numbers_are_jumpers no)
		(fp_line
			(start -0.299974 0.150114)
			(end -0.299974 -0.150114)
			(stroke
				(width 0.1)
				(type default)
			)
			(layer "F.Fab")
		)
		(fp_line
			(start 0.299974 0.150114)
			(end -0.299974 0.150114)
			(stroke
				(width 0.1)
				(type default)
			)
			(layer "F.Fab")
		)
		(fp_line
			(start -0.299974 -0.150114)
			(end 0.299974 -0.150114)
			(stroke
				(width 0.1)
				(type default)
			)
			(layer "F.Fab")
		)
		(fp_line
			(start 0.299974 -0.150114)
			(end 0.299974 0.150114)
			(stroke
				(width 0.1)
				(type default)
			)
			(layer "F.Fab")
		)
		(pad "1" smd rect
			(at -0.2667 0 270)
			(size 0.3048 0.381)
			(layers "F.Cu" "F.Mask" "F.Paste")
			(net "P5E_CPU1_P2_TX_C_DP<9>")
		)
		(pad "2" smd rect
			(at 0.2667 0 270)
			(size 0.3048 0.381)
			(layers "F.Cu" "F.Mask" "F.Paste")
			(net "P5E_CPU1_P2_TX_DP<9>")
		)
	)
)
